# SCM (Grand Teton) — schematic netlist excerpt (pin names and nets, part order shuffled) for the footprints in the layout excerpt that follows; sources: Cadence DE-HDL packaged netlist, KiCad conversion of 12092022_DA0F0TMDCD0_F0T_Management_Board_D_brd_V3_OCP.brd

R392  Q_RES  0 5% CHIP  pkg 0402LF  page 13 : A = RMII_OCP_RCLKI_ISO ; B = RMII_OCP_RCLKI_R_ISO

J7  CONN8_210HP1080BR1  CONN8_210-HP1-080BR1 IO  pkg HEADER1X8XE  page 32
  \1\  = J7_P1
  \2\  = JTAG_SCM_CONN_TDO
  \3\  = JTAG_SCM_CONN_TDI
  \4\  = JTAG_SCM_PLD_R1_JTAGEN
  \5\  = TP_PLD_CONN_P5
  \6\  = JTAG_SCM_CONN_TMS
  \7\  = GND
  \8\  = JTAG_SCM_CONN_TCK

(kicad_pcb
	(version 20260206)
	(generator "pcbnew")
	(generator_version "10.0")
	(general
		(thickness 1.6)
		(legacy_teardrops no)
	)
	(paper "A4")
	(title_block
		(title "12092022_DA0F0TMDCD0_F0T_Management_Board_D_brd_V3_OCP.brd")
		(comment 1 "Grand Teton / footprints 160-161 of 1440")
	)
	(layers
		(0 "F.Cu" signal "TOP")
		(4 "In1.Cu" signal "GND")
		(6 "In2.Cu" signal "IN1")
		(8 "In3.Cu" signal "GND1")
		(10 "In4.Cu" signal "IN2")
		(12 "In5.Cu" signal "VCC")
		(14 "In6.Cu" signal "VCC1")
		(16 "In7.Cu" signal "IN3")
		(18 "In8.Cu" signal "GND2")
		(20 "In9.Cu" signal "IN4")
		(22 "In10.Cu" signal "GND3")
		(2 "B.Cu" signal "BOTTOM")
		(9 "F.Adhes" user "F.Adhesive")
		(11 "B.Adhes" user "B.Adhesive")
		(13 "F.Paste" user "Package Geometry/Pastemask Top")
		(15 "B.Paste" user "Package Geometry/Pastemask Bottom")
		(5 "F.SilkS" user "Ref Des/Silkscreen Top")
		(7 "B.SilkS" user "Ref Des/Silkscreen Bottom")
		(1 "F.Mask" user "Board Geometry/Soldermask Top")
		(3 "B.Mask" user "Board Geometry/Soldermask Bottom")
		(17 "Dwgs.User" user "User.Drawings")
		(19 "Cmts.User" user "User.Comments")
		(21 "Eco1.User" user "User.Eco1")
		(23 "Eco2.User" user "User.Eco2")
		(25 "Edge.Cuts" user "Board Geometry/Outline")
		(27 "Margin" user)
		(31 "F.CrtYd" user "Package Geometry/Place Bound Top")
		(29 "B.CrtYd" user "Package Geometry/Place Bound Bottom")
		(35 "F.Fab" user "Ref Des/Assembly Top")
		(33 "B.Fab" user "Ref Des/Assembly Bottom")
	)
	(footprint ""
		(layer "F.Cu")
		(at 6.050026 -103.925116)
		(property "Reference" "J7"
			(at -4.703826 -0.048514 0)
			(unlocked yes)
			(layer "F.SilkS")
			(effects
				(font
					(size 0.7874 0.5842)
					(thickness 0.1524)
				)
				(justify left)
			)
		)
		(property "Value" ""
			(at 0 0 0)
			(layer "F.Fab")
			(effects
				(font
					(size 1.27 1.27)
				)
			)
		)
		(duplicate_pad_numbers_are_jumpers no)
		(fp_line
			(start -1.249934 -1.320038)
			(end 1.249934 -1.320038)
			(stroke
				(width 0.1524)
				(type default)
			)
			(layer "F.SilkS")
		)
		(fp_line
			(start -1.249934 19.100038)
			(end -1.249934 -1.320038)
			(stroke
				(width 0.1524)
				(type default)
			)
			(layer "F.SilkS")
		)
		(fp_line
			(start 1.249934 -1.320038)
			(end 1.249934 19.100038)
			(stroke
				(width 0.1524)
				(type default)
			)
			(layer "F.SilkS")
		)
		(fp_line
			(start 1.249934 19.100038)
			(end -1.249934 19.100038)
			(stroke
				(width 0.1524)
				(type default)
			)
			(layer "F.SilkS")
		)
		(fp_poly
			(pts
				(xy -2.7432 0.63881) (xy -2.7432 -0.63881) (xy -1.465834 0)
			)
			(stroke
				(width 0)
				(type default)
			)
			(fill yes)
			(layer "F.SilkS")
		)
		(fp_line
			(start -1.249934 -1.320038)
			(end 1.249934 -1.320038)
			(stroke
				(width 0.1)
				(type default)
			)
			(layer "F.Fab")
		)
		(fp_line
			(start -1.249934 19.100038)
			(end -1.249934 -1.320038)
			(stroke
				(width 0.1)
				(type default)
			)
			(layer "F.Fab")
		)
		(fp_line
			(start 1.249934 -1.320038)
			(end 1.249934 19.100038)
			(stroke
				(width 0.1)
				(type default)
			)
			(layer "F.Fab")
		)
		(fp_line
			(start 1.249934 19.100038)
			(end -1.249934 19.100038)
			(stroke
				(width 0.1)
				(type default)
			)
			(layer "F.Fab")
		)
		(fp_poly
			(pts
				(xy -2.7432 0.63881) (xy -2.7432 -0.63881) (xy -1.465834 0)
			)
			(stroke
				(width 0)
				(type default)
			)
			(fill yes)
			(layer "F.Fab")
		)
		(fp_text user "8"
			(at -1.7526 17.80667 0)
			(unlocked yes)
			(layer "F.SilkS")
			(effects
				(font
					(size 0.7874 0.5842)
					(thickness 0.1524)
				)
			)
		)
		(fp_text user "1"
			(at -1.401826 -0.340614 0)
			(unlocked yes)
			(layer "B.SilkS")
			(effects
				(font
					(size 0.7874 0.5842)
					(thickness 0.1524)
				)
				(justify mirror)
			)
		)
		(fp_text user "8"
			(at -1.1938 17.80667 0)
			(unlocked yes)
			(layer "B.SilkS")
			(effects
				(font
					(size 0.7874 0.5842)
					(thickness 0.1524)
				)
				(justify mirror)
			)
		)
		(fp_text user "8"
			(at -1.1938 17.80667 0)
			(unlocked yes)
			(layer "B.Fab")
			(effects
				(font
					(size 0.7874 0.5842)
					(thickness 0.1524)
				)
				(justify mirror)
			)
		)
		(fp_text user "1"
			(at -1.1176 -0.02413 0)
			(unlocked yes)
			(layer "B.Fab")
			(effects
				(font
					(size 0.7874 0.5842)
					(thickness 0.1524)
				)
				(justify mirror)
			)
		)
		(fp_text user "8"
			(at -1.7526 17.80667 0)
			(unlocked yes)
			(layer "F.Fab")
			(effects
				(font
					(size 0.7874 0.5842)
					(thickness 0.1524)
				)
			)
		)
		(pad "1" thru_hole rect
			(at 0 0)
			(size 1.5494 1.5494)
			(drill 1.0414)
			(layers "*.Cu" "*.Mask")
			(remove_unused_layers no)
			(net "J7_P1")
			(clearance 0)
			(padstack
				(mode front_inner_back)
				(layer "Inner"
					(shape circle)
					(size 1.5494 1.5494)
					(clearance 0)
				)
				(layer "B.Cu"
					(shape rect)
					(size 1.5494 1.5494)
					(clearance 0)
				)
			)
		)
		(pad "2" thru_hole circle
			(at 0 2.54)
			(size 1.5494 1.5494)
			(drill 1.0414)
			(layers "*.Cu" "*.Mask")
			(remove_unused_layers no)
			(net "JTAG_SCM_CONN_TDO")
			(clearance 0)
		)
		(pad "3" thru_hole circle
			(at 0 5.08)
			(size 1.5494 1.5494)
			(drill 1.0414)
			(layers "*.Cu" "*.Mask")
			(remove_unused_layers no)
			(net "JTAG_SCM_CONN_TDI")
			(clearance 0)
		)
		(pad "4" thru_hole circle
			(at 0 7.62)
			(size 1.5494 1.5494)
			(drill 1.0414)
			(layers "*.Cu" "*.Mask")
			(remove_unused_layers no)
			(net "JTAG_SCM_PLD_R1_JTAGEN")
			(clearance 0)
		)
		(pad "5" thru_hole circle
			(at 0 10.16)
			(size 1.5494 1.5494)
			(drill 1.0414)
			(layers "*.Cu" "*.Mask")
			(remove_unused_layers no)
			(net "TP_PLD_CONN_P5")
			(clearance 0)
		)
		(pad "6" thru_hole circle
			(at 0 12.7)
			(size 1.5494 1.5494)
			(drill 1.0414)
			(layers "*.Cu" "*.Mask")
			(remove_unused_layers no)
			(net "JTAG_SCM_CONN_TMS")
			(clearance 0)
		)
		(pad "7" thru_hole circle
			(at 0 15.24)
			(size 1.5494 1.5494)
			(drill 1.0414)
			(layers "*.Cu" "*.Mask")
			(remove_unused_layers no)
			(net "GND")
			(clearance 0)
		)
		(pad "8" thru_hole circle
			(at 0 17.78)
			(size 1.5494 1.5494)
			(drill 1.0414)
			(layers "*.Cu" "*.Mask")
			(remove_unused_layers no)
			(net "JTAG_SCM_CONN_TCK")
			(clearance 0)
		)
	)
	(footprint ""
		(layer "F.Cu")
		(at 39.4462 -26.1112 90)
		(property "Reference" "R392"
			(at 0 0 90)
			(layer "F.SilkS")
			(hide yes)
			(effects
				(font
					(size 1.27 1.27)
				)
			)
		)
		(property "Value" ""
			(at 0 0 90)
			(layer "F.Fab")
			(effects
				(font
					(size 1.27 1.27)
				)
			)
		)
		(duplicate_pad_numbers_are_jumpers no)
		(fp_line
			(start 0.7874 -0.4064)
			(end 0.7874 0.4064)
			(stroke
				(width 0.1524)
				(type default)
			)
			(layer "F.SilkS")
		)
		(fp_line
			(start -0.7874 -0.4064)
			(end 0.7874 -0.4064)
			(stroke
				(width 0.1524)
				(type default)
			)
			(layer "F.SilkS")
		)
		(fp_line
			(start 0.7874 0.4064)
			(end -0.7874 0.4064)
			(stroke
				(width 0.1524)
				(type default)
			)
			(layer "F.SilkS")
		)
		(fp_line
			(start -0.7874 0.4064)
			(end -0.7874 -0.4064)
			(stroke
				(width 0.1524)
				(type default)
			)
			(layer "F.SilkS")
		)
		(fp_line
			(start -0.12065 -0.305054)
			(end -0.12065 -0.2794)
			(stroke
				(width 0.1)
				(type default)
			)
			(layer "F.Fab")
		)
		(fp_line
			(start -0.67945 -0.305054)
			(end -0.12065 -0.305054)
			(stroke
				(width 0.1)
				(type default)
			)
			(layer "F.Fab")
		)
		(fp_line
			(start 0.67945 -0.3048)
			(end 0.67945 0.3048)
			(stroke
				(width 0.1)
				(type default)
			)
			(layer "F.Fab")
		)
		(fp_line
			(start 0.12065 -0.3048)
			(end 0.67945 -0.3048)
			(stroke
				(width 0.1)
				(type default)
			)
			(layer "F.Fab")
		)
		(fp_line
			(start 0.12065 -0.2794)
			(end 0.12065 -0.3048)
			(stroke
				(width 0.1)
				(type default)
			)
			(layer "F.Fab")
		)
		(fp_line
			(start -0.12065 -0.2794)
			(end 0.12065 -0.2794)
			(stroke
				(width 0.1)
				(type default)
			)
			(layer "F.Fab")
		)
		(fp_line
			(start 0.120396 0.2794)
			(end -0.12065 0.2794)
			(stroke
				(width 0.1)
				(type default)
			)
			(layer "F.Fab")
		)
		(fp_line
			(start -0.12065 0.2794)
			(end -0.12065 0.3048)
			(stroke
				(width 0.1)
				(type default)
			)
			(layer "F.Fab")
		)
		(fp_line
			(start 0.67945 0.3048)
			(end 0.120396 0.3048)
			(stroke
				(width 0.1)
				(type default)
			)
			(layer "F.Fab")
		)
		(fp_line
			(start 0.120396 0.3048)
			(end 0.120396 0.2794)
			(stroke
				(width 0.1)
				(type default)
			)
			(layer "F.Fab")
		)
		(fp_line
			(start -0.12065 0.3048)
			(end -0.67945 0.3048)
			(stroke
				(width 0.1)
				(type default)
			)
			(layer "F.Fab")
		)
		(fp_line
			(start -0.67945 0.3048)
			(end -0.67945 -0.305054)
			(stroke
				(width 0.1)
				(type default)
			)
			(layer "F.Fab")
		)
		(pad "1" smd circle
			(at -0.40005 0 90)
			(size 0 0)
			(layers "F.Cu" "F.Mask" "F.Paste")
			(net "RMII_OCP_RCLKI_ISO")
		)
		(pad "2" smd circle
			(at 0.40005 0 90)
			(size 0 0)
			(layers "F.Cu" "F.Mask" "F.Paste")
			(net "RMII_OCP_RCLKI_R_ISO")
		)
	)
)
